(kicad_pcb
	(version 20260206)
	(generator "pcbnew")
	(generator_version "10.0")
	(general
		(thickness 1.6)
		(legacy_teardrops no)
	)
	(paper "A4")
	(title_block
		(title "Bryce Canyon_R.DPB_16317-1_OCP.brd")
		(comment 1 "Bryce Canyon / footprints 873-879 of 2099")
	)
	(layers
		(0 "F.Cu" signal "TOP")
		(4 "In1.Cu" signal "L2GND")
		(6 "In2.Cu" signal "L3")
		(8 "In3.Cu" signal "L4VCC")
		(10 "In4.Cu" signal "L5VCC")
		(12 "In5.Cu" signal "L6")
		(14 "In6.Cu" signal "L7GND")
		(2 "B.Cu" signal "BOTTOM")
		(9 "F.Adhes" user "F.Adhesive")
		(11 "B.Adhes" user "B.Adhesive")
		(13 "F.Paste" user "Package Geometry/Pastemask Top")
		(15 "B.Paste" user "Package Geometry/Pastemask Bottom")
		(5 "F.SilkS" user "Ref Des/Silkscreen Top")
		(7 "B.SilkS" user "Ref Des/Silkscreen Bottom")
		(1 "F.Mask" user "Board Geometry/Soldermask Top")
		(3 "B.Mask" user "Board Geometry/Soldermask Bottom")
		(17 "Dwgs.User" user "User.Drawings")
		(19 "Cmts.User" user "User.Comments")
		(21 "Eco1.User" user "User.Eco1")
		(23 "Eco2.User" user "User.Eco2")
		(25 "Edge.Cuts" user "Board Geometry/Outline")
		(27 "Margin" user)
		(31 "F.CrtYd" user "Package Geometry/Place Bound Top")
		(29 "B.CrtYd" user "Package Geometry/Place Bound Bottom")
		(35 "F.Fab" user "Ref Des/Assembly Top")
		(33 "B.Fab" user "Ref Des/Assembly Bottom")
	)
	(footprint ""
		(layer "F.Cu")
		(at 332.105 -128.651)
		(property "Reference" "R496"
			(at 0 0 0)
			(layer "F.SilkS")
			(hide yes)
			(effects
				(font
					(size 1.27 1.27)
				)
			)
		)
		(property "Value" "4K7R2F-GP"
			(at 0.064008 -3.993896 0)
			(unlocked yes)
			(layer "F.Fab")
			(hide yes)
			(effects
				(font
					(size 1.016 1.016)
					(thickness 0.1524)
				)
			)
		)
		(property "Device Type" "R402H16"
			(at 0.064008 -5.517896 0)
			(unlocked yes)
			(layer "F.Fab")
			(hide yes)
			(effects
				(font
					(size 1.016 1.016)
					(thickness 0.1524)
				)
			)
		)
		(duplicate_pad_numbers_are_jumpers no)
		(fp_line
			(start -0.508 -0.9398)
			(end -0.508 0.9398)
			(stroke
				(width 0.1524)
				(type default)
			)
			(layer "F.SilkS")
		)
		(fp_line
			(start 0.508 -0.9398)
			(end -0.508 -0.9398)
			(stroke
				(width 0.1524)
				(type default)
			)
			(layer "F.SilkS")
		)
		(fp_rect
			(start -0.508 0.9398)
			(end 0.508 -0.9398)
			(stroke
				(width 0)
				(type default)
			)
			(fill no)
			(layer "F.CrtYd")
		)
		(fp_rect
			(start -0.508 0.9398)
			(end 0.508 -0.9398)
			(stroke
				(width 0)
				(type default)
			)
			(fill no)
			(layer "F.Fab")
		)
		(pad "1" smd custom
			(at 0 -0.4445)
			(size 0.1397 0.1397)
			(layers "F.Cu" "F.Mask" "F.Paste")
			(net "SW_PWR_R_HDD18")
			(options
				(clearance outline)
				(anchor circle)
			)
			(primitives
				(gr_poly
					(pts
						(arc
							(start -0.1778 -0.2794)
							(mid -0.249642 -0.249642)
							(end -0.2794 -0.1778)
						)
						(arc
							(start -0.2794 0.1778)
							(mid -0.249642 0.249642)
							(end -0.1778 0.2794)
						)
						(arc
							(start 0.1778 0.2794)
							(mid 0.249642 0.249642)
							(end 0.2794 0.1778)
						)
						(arc
							(start 0.2794 -0.1778)
							(mid 0.249642 -0.249642)
							(end 0.1778 -0.2794)
						)
					)
					(width 0)
					(fill yes)
				)
			)
		)
		(pad "2" smd custom
			(at 0 0.4445)
			(size 0.1397 0.1397)
			(layers "F.Cu" "F.Mask" "F.Paste")
			(net "GND")
			(options
				(clearance outline)
				(anchor circle)
			)
			(primitives
				(gr_poly
					(pts
						(arc
							(start -0.1778 -0.2794)
							(mid -0.249642 -0.249642)
							(end -0.2794 -0.1778)
						)
						(arc
							(start -0.2794 0.1778)
							(mid -0.249642 0.249642)
							(end -0.1778 0.2794)
						)
						(arc
							(start 0.1778 0.2794)
							(mid 0.249642 0.249642)
							(end 0.2794 0.1778)
						)
						(arc
							(start 0.2794 -0.1778)
							(mid 0.249642 -0.249642)
							(end 0.1778 -0.2794)
						)
					)
					(width 0)
					(fill yes)
				)
			)
		)
	)
	(footprint ""
		(layer "F.Cu")
		(at 114.681 -32.004 -90)
		(property "Reference" "C382"
			(at 0 0 270)
			(layer "F.SilkS")
			(hide yes)
			(effects
				(font
					(size 1.27 1.27)
				)
			)
		)
		(property "Value" "SC10U16V6KX-2GP"
			(at -0.0762 -5.1308 270)
			(unlocked yes)
			(layer "F.Fab")
			(hide yes)
			(effects
				(font
					(size 1.016 1.016)
					(thickness 0.1524)
				)
			)
		)
		(property "Device Type" "C1206H71"
			(at -0.127 -6.6548 270)
			(unlocked yes)
			(layer "F.Fab")
			(hide yes)
			(effects
				(font
					(size 1.016 1.016)
					(thickness 0.1524)
				)
			)
		)
		(duplicate_pad_numbers_are_jumpers no)
		(fp_line
			(start -1.016 2.2352)
			(end -1.016 0.8382)
			(stroke
				(width 0.1524)
				(type default)
			)
			(layer "F.SilkS")
		)
		(fp_line
			(start 1.016 2.2352)
			(end -1.016 2.2352)
			(stroke
				(width 0.1524)
				(type default)
			)
			(layer "F.SilkS")
		)
		(fp_line
			(start 1.016 0.8382)
			(end 1.016 2.2352)
			(stroke
				(width 0.1524)
				(type default)
			)
			(layer "F.SilkS")
		)
		(fp_line
			(start -1.016 -0.8382)
			(end -1.016 -2.2352)
			(stroke
				(width 0.1524)
				(type default)
			)
			(layer "F.SilkS")
		)
		(fp_line
			(start -1.016 -2.2352)
			(end 1.016 -2.2352)
			(stroke
				(width 0.1524)
				(type default)
			)
			(layer "F.SilkS")
		)
		(fp_line
			(start 1.016 -2.2352)
			(end 1.016 -0.8382)
			(stroke
				(width 0.1524)
				(type default)
			)
			(layer "F.SilkS")
		)
		(fp_rect
			(start -1.0922 2.3114)
			(end 1.0922 -2.3114)
			(stroke
				(width 0)
				(type default)
			)
			(fill no)
			(layer "F.CrtYd")
		)
		(fp_poly
			(pts
				(xy 1.0922 -2.3114) (xy 1.0922 2.3114) (xy -1.0922 2.3114) (xy -1.0922 -2.3114)
			)
			(stroke
				(width 0)
				(type default)
			)
			(fill no)
			(layer "F.Fab")
		)
		(pad "1" smd rect
			(at 0 -1.397 270)
			(size 1.651 1.27)
			(layers "F.Cu" "F.Mask" "F.Paste")
			(net "P5V_HDD27")
		)
		(pad "2" smd rect
			(at 0 1.397 270)
			(size 1.651 1.27)
			(layers "F.Cu" "F.Mask" "F.Paste")
			(net "GND")
		)
	)
	(footprint ""
		(layer "F.Cu")
		(at 399.923 -263.017)
		(property "Reference" "Q32"
			(at 0 0 0)
			(layer "F.SilkS")
			(hide yes)
			(effects
				(font
					(size 1.27 1.27)
				)
			)
		)
		(property "Value" "AO4407AL-GP"
			(at -3.707384 -1.5367 0)
			(unlocked yes)
			(layer "F.Fab")
			(hide yes)
			(effects
				(font
					(size 1.016 1.016)
					(thickness 0.1524)
				)
			)
		)
		(property "Device Type" "SOIC8H69"
			(at -3.707384 -3.0607 0)
			(unlocked yes)
			(layer "F.Fab")
			(hide yes)
			(effects
				(font
					(size 1.016 1.016)
					(thickness 0.1524)
				)
			)
		)
		(duplicate_pad_numbers_are_jumpers no)
		(fp_line
			(start -2.7432 -1.4224)
			(end -2.7432 1.4224)
			(stroke
				(width 0.1524)
				(type default)
			)
			(layer "F.SilkS")
		)
		(fp_line
			(start -2.7432 1.4224)
			(end -2.6416 1.4224)
			(stroke
				(width 0.1524)
				(type default)
			)
			(layer "F.SilkS")
		)
		(fp_line
			(start -2.7432 1.4224)
			(end 2.1336 1.4224)
			(stroke
				(width 0.1524)
				(type default)
			)
			(layer "F.SilkS")
		)
		(fp_line
			(start -2.7178 -0.508)
			(end -2.1844 -0.0508)
			(stroke
				(width 0.1524)
				(type default)
			)
			(layer "F.SilkS")
		)
		(fp_line
			(start -2.6289 3.4417)
			(end -2.6289 1.4732)
			(stroke
				(width 0.381)
				(type default)
			)
			(layer "F.SilkS")
		)
		(fp_line
			(start -2.1844 -0.0508)
			(end -2.7178 0.508)
			(stroke
				(width 0.1524)
				(type default)
			)
			(layer "F.SilkS")
		)
		(fp_line
			(start 2.1336 -1.4224)
			(end -2.7432 -1.4224)
			(stroke
				(width 0.1524)
				(type default)
			)
			(layer "F.SilkS")
		)
		(fp_line
			(start 2.1336 1.4224)
			(end 2.1336 -1.4224)
			(stroke
				(width 0.1524)
				(type default)
			)
			(layer "F.SilkS")
		)
		(fp_poly
			(pts
				(xy -2.2098 -1.4224) (xy -2.2098 1.4224) (xy 2.2098 1.4224) (xy 2.2098 -1.4224)
			)
			(stroke
				(width 0)
				(type default)
			)
			(fill yes)
			(layer "F.SilkS")
		)
		(fp_rect
			(start -2.450084 2.999994)
			(end 2.450084 -2.999994)
			(stroke
				(width 0)
				(type default)
			)
			(fill no)
			(layer "F.CrtYd")
		)
		(fp_poly
			(pts
				(xy -2.8194 3.6322) (xy -2.8194 -3.6322) (xy 2.8194 -3.6322) (xy 2.8194 1.18364) (xy 2.450084 1.18364)
				(xy 2.450084 -2.999994) (xy -2.450084 -2.999994) (xy -2.450084 2.999994) (xy 2.450084 2.999994)
				(xy 2.450084 1.18618) (xy 2.8194 1.18618) (xy 2.8194 3.6322)
			)
			(stroke
				(width 0)
				(type default)
			)
			(fill no)
			(layer "F.CrtYd")
		)
		(fp_rect
			(start -2.8194 3.6322)
			(end 2.8194 -3.6322)
			(stroke
				(width 0)
				(type default)
			)
			(fill no)
			(layer "F.Fab")
		)
		(pad "1" smd rect
			(at -1.905 2.54)
			(size 0.635 1.651)
			(layers "F.Cu" "F.Mask" "F.Paste")
			(net "P12V_B")
		)
		(pad "2" smd rect
			(at -0.635 2.54)
			(size 0.635 1.651)
			(layers "F.Cu" "F.Mask" "F.Paste")
			(net "P12V_B")
		)
		(pad "3" smd rect
			(at 0.635 2.54)
			(size 0.635 1.651)
			(layers "F.Cu" "F.Mask" "F.Paste")
			(net "P12V_B")
		)
		(pad "4" smd rect
			(at 1.905 2.54)
			(size 0.635 1.651)
			(layers "F.Cu" "F.Mask" "F.Paste")
			(net "SW_HDD_N8")
		)
		(pad "5" smd rect
			(at 1.905 -2.54)
			(size 0.635 1.651)
			(layers "F.Cu" "F.Mask" "F.Paste")
			(net "P12V_HDD8")
		)
		(pad "6" smd rect
			(at 0.635 -2.54)
			(size 0.635 1.651)
			(layers "F.Cu" "F.Mask" "F.Paste")
			(net "P12V_HDD8")
		)
		(pad "7" smd rect
			(at -0.635 -2.54)
			(size 0.635 1.651)
			(layers "F.Cu" "F.Mask" "F.Paste")
			(net "P12V_HDD8")
		)
		(pad "8" smd rect
			(at -1.905 -2.54)
			(size 0.635 1.651)
			(layers "F.Cu" "F.Mask" "F.Paste")
			(net "P12V_HDD8")
		)
	)
	(footprint ""
		(layer "F.Cu")
		(at 310.82742 -327.858882)
		(property "Reference" "R115"
			(at 0 0 0)
			(layer "F.SilkS")
			(hide yes)
			(effects
				(font
					(size 1.27 1.27)
				)
			)
		)
		(property "Value" "100KR2F-L1-GP"
			(at 0.064008 -3.993896 0)
			(unlocked yes)
			(layer "F.Fab")
			(hide yes)
			(effects
				(font
					(size 1.016 1.016)
					(thickness 0.1524)
				)
			)
		)
		(property "Device Type" "R402H16"
			(at 0.064008 -5.517896 0)
			(unlocked yes)
			(layer "F.Fab")
			(hide yes)
			(effects
				(font
					(size 1.016 1.016)
					(thickness 0.1524)
				)
			)
		)
		(duplicate_pad_numbers_are_jumpers no)
		(fp_line
			(start -0.508 -0.9398)
			(end -0.508 0.9398)
			(stroke
				(width 0.1524)
				(type default)
			)
			(layer "F.SilkS")
		)
		(fp_line
			(start 0.508 -0.9398)
			(end -0.508 -0.9398)
			(stroke
				(width 0.1524)
				(type default)
			)
			(layer "F.SilkS")
		)
		(fp_rect
			(start -0.508 0.9398)
			(end 0.508 -0.9398)
			(stroke
				(width 0)
				(type default)
			)
			(fill no)
			(layer "F.CrtYd")
		)
		(fp_rect
			(start -0.508 0.9398)
			(end 0.508 -0.9398)
			(stroke
				(width 0)
				(type default)
			)
			(fill no)
			(layer "F.Fab")
		)
		(pad "1" smd custom
			(at 0 -0.4445)
			(size 0.1397 0.1397)
			(layers "F.Cu" "F.Mask" "F.Paste")
			(net "PWM_SCC_A_ZONE_D")
			(options
				(clearance outline)
				(anchor circle)
			)
			(primitives
				(gr_poly
					(pts
						(arc
							(start -0.1778 -0.2794)
							(mid -0.249642 -0.249642)
							(end -0.2794 -0.1778)
						)
						(arc
							(start -0.2794 0.1778)
							(mid -0.249642 0.249642)
							(end -0.1778 0.2794)
						)
						(arc
							(start 0.1778 0.2794)
							(mid 0.249642 0.249642)
							(end 0.2794 0.1778)
						)
						(arc
							(start 0.2794 -0.1778)
							(mid 0.249642 -0.249642)
							(end 0.1778 -0.2794)
						)
					)
					(width 0)
					(fill yes)
				)
			)
		)
		(pad "2" smd custom
			(at 0 0.4445)
			(size 0.1397 0.1397)
			(layers "F.Cu" "F.Mask" "F.Paste")
			(net "GND")
			(options
				(clearance outline)
				(anchor circle)
			)
			(primitives
				(gr_poly
					(pts
						(arc
							(start -0.1778 -0.2794)
							(mid -0.249642 -0.249642)
							(end -0.2794 -0.1778)
						)
						(arc
							(start -0.2794 0.1778)
							(mid -0.249642 0.249642)
							(end -0.1778 0.2794)
						)
						(arc
							(start 0.1778 0.2794)
							(mid 0.249642 0.249642)
							(end 0.2794 0.1778)
						)
						(arc
							(start 0.2794 -0.1778)
							(mid 0.249642 -0.249642)
							(end 0.1778 -0.2794)
						)
					)
					(width 0)
					(fill yes)
				)
			)
		)
	)
	(footprint ""
		(layer "F.Cu")
		(at 256.484374 -229.38105 -90)
		(property "Reference" "R166"
			(at 0 0 270)
			(layer "F.SilkS")
			(hide yes)
			(effects
				(font
					(size 1.27 1.27)
				)
			)
		)
		(property "Value" "16K2R2F-GP"
			(at 0.064008 -3.993896 270)
			(unlocked yes)
			(layer "F.Fab")
			(hide yes)
			(effects
				(font
					(size 1.016 1.016)
					(thickness 0.1524)
				)
			)
		)
		(property "Device Type" "R402H16"
			(at 0.064008 -5.517896 270)
			(unlocked yes)
			(layer "F.Fab")
			(hide yes)
			(effects
				(font
					(size 1.016 1.016)
					(thickness 0.1524)
				)
			)
		)
		(duplicate_pad_numbers_are_jumpers no)
		(fp_line
			(start -0.508 -0.9398)
			(end -0.508 0.9398)
			(stroke
				(width 0.1524)
				(type default)
			)
			(layer "F.SilkS")
		)
		(fp_line
			(start 0.508 -0.9398)
			(end -0.508 -0.9398)
			(stroke
				(width 0.1524)
				(type default)
			)
			(layer "F.SilkS")
		)
		(fp_rect
			(start -0.508 0.9398)
			(end 0.508 -0.9398)
			(stroke
				(width 0)
				(type default)
			)
			(fill no)
			(layer "F.CrtYd")
		)
		(fp_rect
			(start -0.508 0.9398)
			(end 0.508 -0.9398)
			(stroke
				(width 0)
				(type default)
			)
			(fill no)
			(layer "F.Fab")
		)
		(pad "1" smd custom
			(at 0 -0.4445 270)
			(size 0.1397 0.1397)
			(layers "F.Cu" "F.Mask" "F.Paste")
			(net "P5V_B_2")
			(options
				(clearance outline)
				(anchor circle)
			)
			(primitives
				(gr_poly
					(pts
						(arc
							(start -0.1778 -0.2794)
							(mid -0.249642 -0.249642)
							(end -0.2794 -0.1778)
						)
						(arc
							(start -0.2794 0.1778)
							(mid -0.249642 0.249642)
							(end -0.1778 0.2794)
						)
						(arc
							(start 0.1778 0.2794)
							(mid 0.249642 0.249642)
							(end 0.2794 0.1778)
						)
						(arc
							(start 0.2794 -0.1778)
							(mid 0.249642 -0.249642)
							(end 0.1778 -0.2794)
						)
					)
					(width 0)
					(fill yes)
				)
			)
		)
		(pad "2" smd custom
			(at 0 0.4445 270)
			(size 0.1397 0.1397)
			(layers "F.Cu" "F.Mask" "F.Paste")
			(net "P5V_B_2_SENSE")
			(options
				(clearance outline)
				(anchor circle)
			)
			(primitives
				(gr_poly
					(pts
						(arc
							(start -0.1778 -0.2794)
							(mid -0.249642 -0.249642)
							(end -0.2794 -0.1778)
						)
						(arc
							(start -0.2794 0.1778)
							(mid -0.249642 0.249642)
							(end -0.1778 0.2794)
						)
						(arc
							(start 0.1778 0.2794)
							(mid 0.249642 0.249642)
							(end 0.2794 0.1778)
						)
						(arc
							(start 0.2794 -0.1778)
							(mid 0.249642 -0.249642)
							(end 0.1778 -0.2794)
						)
					)
					(width 0)
					(fill yes)
				)
			)
		)
	)
	(footprint ""
		(layer "F.Cu")
		(at 66.313812 -39.705026)
		(property "Reference" "TP146"
			(at 0 0 0)
			(layer "F.SilkS")
			(hide yes)
			(effects
				(font
					(size 1.27 1.27)
				)
			)
		)
		(property "Value" "*"
			(at -0.0508 -1.6764 0)
			(unlocked yes)
			(layer "F.Fab")
			(hide yes)
			(effects
				(font
					(size 1.016 1.016)
					(thickness 0.1524)
				)
			)
		)
		(property "Device Type" "TPAD32"
			(at -0.0508 -3.2004 0)
			(unlocked yes)
			(layer "F.Fab")
			(hide yes)
			(effects
				(font
					(size 1.016 1.016)
					(thickness 0.1524)
				)
			)
		)
		(duplicate_pad_numbers_are_jumpers no)
		(fp_poly
			(pts
				(arc
					(start 0.4064 0)
					(mid -0.4064 0)
					(end 0.4064 0)
				)
			)
			(stroke
				(width 0)
				(type default)
			)
			(fill no)
			(layer "F.CrtYd")
		)
		(fp_poly
			(pts
				(arc
					(start 0.7112 0)
					(mid -0.7112 0)
					(end 0.7112 0)
				)
			)
			(stroke
				(width 0)
				(type default)
			)
			(fill no)
			(layer "F.Fab")
		)
		(pad "1" smd circle
			(at 0 0)
			(size 0.8128 0.8128)
			(layers "F.Cu" "F.Mask" "F.Paste")
			(net "ACT_HDD_25")
		)
	)
	(footprint ""
		(layer "F.Cu")
		(at 335.788 -131.826 180)
		(property "Reference" "R501"
			(at 0 0 180)
			(layer "F.SilkS")
			(hide yes)
			(effects
				(font
					(size 1.27 1.27)
				)
			)
		)
		(property "Value" "0R2J-2-GP"
			(at 0.064008 -3.993896 180)
			(unlocked yes)
			(layer "F.Fab")
			(hide yes)
			(effects
				(font
					(size 1.016 1.016)
					(thickness 0.1524)
				)
			)
		)
		(property "Device Type" "R402H16"
			(at 0.064008 -5.517896 180)
			(unlocked yes)
			(layer "F.Fab")
			(hide yes)
			(effects
				(font
					(size 1.016 1.016)
					(thickness 0.1524)
				)
			)
		)
		(duplicate_pad_numbers_are_jumpers no)
		(fp_line
			(start 0.508 -0.9398)
			(end -0.508 -0.9398)
			(stroke
				(width 0.1524)
				(type default)
			)
			(layer "F.SilkS")
		)
		(fp_line
			(start -0.508 -0.9398)
			(end -0.508 0.9398)
			(stroke
				(width 0.1524)
				(type default)
			)
			(layer "F.SilkS")
		)
		(fp_rect
			(start -0.508 0.9398)
			(end 0.508 -0.9398)
			(stroke
				(width 0)
				(type default)
			)
			(fill no)
			(layer "F.CrtYd")
		)
		(fp_rect
			(start -0.508 0.9398)
			(end 0.508 -0.9398)
			(stroke
				(width 0)
				(type default)
			)
			(fill no)
			(layer "F.Fab")
		)
		(pad "1" smd custom
			(at 0 -0.4445 180)
			(size 0.1397 0.1397)
			(layers "F.Cu" "F.Mask" "F.Paste")
			(net "SW_HDD_G18")
			(options
				(clearance outline)
				(anchor circle)
			)
			(primitives
				(gr_poly
					(pts
						(arc
							(start -0.1778 -0.2794)
							(mid -0.249642 -0.249642)
							(end -0.2794 -0.1778)
						)
						(arc
							(start -0.2794 0.1778)
							(mid -0.249642 0.249642)
							(end -0.1778 0.2794)
						)
						(arc
							(start 0.1778 0.2794)
							(mid 0.249642 0.249642)
							(end 0.2794 0.1778)
						)
						(arc
							(start 0.2794 -0.1778)
							(mid 0.249642 -0.249642)
							(end 0.1778 -0.2794)
						)
					)
					(width 0)
					(fill yes)
				)
			)
		)
		(pad "2" smd custom
			(at 0 0.4445 180)
			(size 0.1397 0.1397)
			(layers "F.Cu" "F.Mask" "F.Paste")
			(net "SW_HDD_R18")
			(options
				(clearance outline)
				(anchor circle)
			)
			(primitives
				(gr_poly
					(pts
						(arc
							(start -0.1778 -0.2794)
							(mid -0.249642 -0.249642)
							(end -0.2794 -0.1778)
						)
						(arc
							(start -0.2794 0.1778)
							(mid -0.249642 0.249642)
							(end -0.1778 0.2794)
						)
						(arc
							(start 0.1778 0.2794)
							(mid 0.249642 0.249642)
							(end 0.2794 0.1778)
						)
						(arc
							(start 0.2794 -0.1778)
							(mid 0.249642 -0.249642)
							(end 0.1778 -0.2794)
						)
					)
					(width 0)
					(fill yes)
				)
			)
		)
	)
)
